(kicad_pcb
	(version 20260206)
	(generator "pcbnew")
	(generator_version "10.0")
	(general
		(thickness 1.6)
		(legacy_teardrops no)
	)
	(paper "A4")
	(title_block
		(title "Bryce Canyon_R.DPB_16317-1_OCP.brd")
		(comment 1 "Bryce Canyon / footprints 51-57 of 2099")
	)
	(layers
		(0 "F.Cu" signal "TOP")
		(4 "In1.Cu" signal "L2GND")
		(6 "In2.Cu" signal "L3")
		(8 "In3.Cu" signal "L4VCC")
		(10 "In4.Cu" signal "L5VCC")
		(12 "In5.Cu" signal "L6")
		(14 "In6.Cu" signal "L7GND")
		(2 "B.Cu" signal "BOTTOM")
		(9 "F.Adhes" user "F.Adhesive")
		(11 "B.Adhes" user "B.Adhesive")
		(13 "F.Paste" user "Package Geometry/Pastemask Top")
		(15 "B.Paste" user "Package Geometry/Pastemask Bottom")
		(5 "F.SilkS" user "Ref Des/Silkscreen Top")
		(7 "B.SilkS" user "Ref Des/Silkscreen Bottom")
		(1 "F.Mask" user "Board Geometry/Soldermask Top")
		(3 "B.Mask" user "Board Geometry/Soldermask Bottom")
		(17 "Dwgs.User" user "User.Drawings")
		(19 "Cmts.User" user "User.Comments")
		(21 "Eco1.User" user "User.Eco1")
		(23 "Eco2.User" user "User.Eco2")
		(25 "Edge.Cuts" user "Board Geometry/Outline")
		(27 "Margin" user)
		(31 "F.CrtYd" user "Package Geometry/Place Bound Top")
		(29 "B.CrtYd" user "Package Geometry/Place Bound Bottom")
		(35 "F.Fab" user "Ref Des/Assembly Top")
		(33 "B.Fab" user "Ref Des/Assembly Bottom")
	)
	(footprint ""
		(layer "F.Cu")
		(at 251.394468 -222.9612)
		(property "Reference" "R111"
			(at 0 0 0)
			(layer "F.SilkS")
			(hide yes)
			(effects
				(font
					(size 1.27 1.27)
				)
			)
		)
		(property "Value" "4K7R2F-GP"
			(at 0.064008 -3.993896 0)
			(unlocked yes)
			(layer "F.Fab")
			(hide yes)
			(effects
				(font
					(size 1.016 1.016)
					(thickness 0.1524)
				)
			)
		)
		(property "Device Type" "R402H16"
			(at 0.064008 -5.517896 0)
			(unlocked yes)
			(layer "F.Fab")
			(hide yes)
			(effects
				(font
					(size 1.016 1.016)
					(thickness 0.1524)
				)
			)
		)
		(duplicate_pad_numbers_are_jumpers no)
		(fp_line
			(start -0.508 -0.9398)
			(end -0.508 0.9398)
			(stroke
				(width 0.1524)
				(type default)
			)
			(layer "F.SilkS")
		)
		(fp_line
			(start 0.508 -0.9398)
			(end -0.508 -0.9398)
			(stroke
				(width 0.1524)
				(type default)
			)
			(layer "F.SilkS")
		)
		(fp_rect
			(start -0.508 0.9398)
			(end 0.508 -0.9398)
			(stroke
				(width 0)
				(type default)
			)
			(fill no)
			(layer "F.CrtYd")
		)
		(fp_rect
			(start -0.508 0.9398)
			(end 0.508 -0.9398)
			(stroke
				(width 0)
				(type default)
			)
			(fill no)
			(layer "F.Fab")
		)
		(pad "1" smd custom
			(at 0 -0.4445)
			(size 0.1397 0.1397)
			(layers "F.Cu" "F.Mask" "F.Paste")
			(net "P3V3_STBY_B")
			(options
				(clearance outline)
				(anchor circle)
			)
			(primitives
				(gr_poly
					(pts
						(arc
							(start -0.1778 -0.2794)
							(mid -0.249642 -0.249642)
							(end -0.2794 -0.1778)
						)
						(arc
							(start -0.2794 0.1778)
							(mid -0.249642 0.249642)
							(end -0.1778 0.2794)
						)
						(arc
							(start 0.1778 0.2794)
							(mid 0.249642 0.249642)
							(end 0.2794 0.1778)
						)
						(arc
							(start 0.2794 -0.1778)
							(mid 0.249642 -0.249642)
							(end 0.1778 -0.2794)
						)
					)
					(width 0)
					(fill yes)
				)
			)
		)
		(pad "2" smd custom
			(at 0 0.4445)
			(size 0.1397 0.1397)
			(layers "F.Cu" "F.Mask" "F.Paste")
			(net "EEPROM_A0")
			(options
				(clearance outline)
				(anchor circle)
			)
			(primitives
				(gr_poly
					(pts
						(arc
							(start -0.1778 -0.2794)
							(mid -0.249642 -0.249642)
							(end -0.2794 -0.1778)
						)
						(arc
							(start -0.2794 0.1778)
							(mid -0.249642 0.249642)
							(end -0.1778 0.2794)
						)
						(arc
							(start 0.1778 0.2794)
							(mid 0.249642 0.249642)
							(end 0.2794 0.1778)
						)
						(arc
							(start 0.2794 -0.1778)
							(mid 0.249642 -0.249642)
							(end 0.1778 -0.2794)
						)
					)
					(width 0)
					(fill yes)
				)
			)
		)
	)
	(footprint ""
		(layer "F.Cu")
		(at 111.379 -253.111 90)
		(property "Reference" "R211"
			(at 0 0 90)
			(layer "F.SilkS")
			(hide yes)
			(effects
				(font
					(size 1.27 1.27)
				)
			)
		)
		(property "Value" "4K7R2J-2-GP"
			(at 0.064008 -3.993896 90)
			(unlocked yes)
			(layer "F.Fab")
			(hide yes)
			(effects
				(font
					(size 1.016 1.016)
					(thickness 0.1524)
				)
			)
		)
		(property "Device Type" "R402H16"
			(at 0.064008 -5.517896 90)
			(unlocked yes)
			(layer "F.Fab")
			(hide yes)
			(effects
				(font
					(size 1.016 1.016)
					(thickness 0.1524)
				)
			)
		)
		(duplicate_pad_numbers_are_jumpers no)
		(fp_line
			(start 0.508 -0.9398)
			(end -0.508 -0.9398)
			(stroke
				(width 0.1524)
				(type default)
			)
			(layer "F.SilkS")
		)
		(fp_line
			(start -0.508 -0.9398)
			(end -0.508 0.9398)
			(stroke
				(width 0.1524)
				(type default)
			)
			(layer "F.SilkS")
		)
		(fp_rect
			(start -0.508 0.9398)
			(end 0.508 -0.9398)
			(stroke
				(width 0)
				(type default)
			)
			(fill no)
			(layer "F.CrtYd")
		)
		(fp_rect
			(start -0.508 0.9398)
			(end 0.508 -0.9398)
			(stroke
				(width 0)
				(type default)
			)
			(fill no)
			(layer "F.Fab")
		)
		(pad "1" smd custom
			(at 0 -0.4445 90)
			(size 0.1397 0.1397)
			(layers "F.Cu" "F.Mask" "F.Paste")
			(net "P12V_B")
			(options
				(clearance outline)
				(anchor circle)
			)
			(primitives
				(gr_poly
					(pts
						(arc
							(start -0.1778 -0.2794)
							(mid -0.249642 -0.249642)
							(end -0.2794 -0.1778)
						)
						(arc
							(start -0.2794 0.1778)
							(mid -0.249642 0.249642)
							(end -0.1778 0.2794)
						)
						(arc
							(start 0.1778 0.2794)
							(mid 0.249642 0.249642)
							(end 0.2794 0.1778)
						)
						(arc
							(start 0.2794 -0.1778)
							(mid 0.249642 -0.249642)
							(end 0.1778 -0.2794)
						)
					)
					(width 0)
					(fill yes)
				)
			)
		)
		(pad "2" smd custom
			(at 0 0.4445 90)
			(size 0.1397 0.1397)
			(layers "F.Cu" "F.Mask" "F.Paste")
			(net "SW_HDD_P3")
			(options
				(clearance outline)
				(anchor circle)
			)
			(primitives
				(gr_poly
					(pts
						(arc
							(start -0.1778 -0.2794)
							(mid -0.249642 -0.249642)
							(end -0.2794 -0.1778)
						)
						(arc
							(start -0.2794 0.1778)
							(mid -0.249642 0.249642)
							(end -0.1778 0.2794)
						)
						(arc
							(start 0.1778 0.2794)
							(mid 0.249642 0.249642)
							(end 0.2794 0.1778)
						)
						(arc
							(start 0.2794 -0.1778)
							(mid 0.249642 -0.249642)
							(end 0.1778 -0.2794)
						)
					)
					(width 0)
					(fill yes)
				)
			)
		)
	)
	(footprint ""
		(layer "F.Cu")
		(at 377.698 -99.187)
		(property "Reference" "R436"
			(at 0 0 0)
			(layer "F.SilkS")
			(hide yes)
			(effects
				(font
					(size 1.27 1.27)
				)
			)
		)
		(property "Value" "130R3F-GP"
			(at -0.0254 -2.5146 0)
			(unlocked yes)
			(layer "F.Fab")
			(hide yes)
			(effects
				(font
					(size 1.016 1.016)
					(thickness 0.1524)
				)
			)
		)
		(property "Device Type" "R603H22"
			(at -0.0254 -4.0386 0)
			(unlocked yes)
			(layer "F.Fab")
			(hide yes)
			(effects
				(font
					(size 1.016 1.016)
					(thickness 0.1524)
				)
			)
		)
		(duplicate_pad_numbers_are_jumpers no)
		(fp_line
			(start -0.4826 0)
			(end -0.2032 0)
			(stroke
				(width 0.2032)
				(type default)
			)
			(layer "F.SilkS")
		)
		(fp_line
			(start 0.2032 0)
			(end 0.4826 0)
			(stroke
				(width 0.2032)
				(type default)
			)
			(layer "F.SilkS")
		)
		(fp_rect
			(start -0.5842 1.3335)
			(end 0.5842 -1.3335)
			(stroke
				(width 0)
				(type default)
			)
			(fill no)
			(layer "F.CrtYd")
		)
		(fp_rect
			(start -0.5842 1.3335)
			(end 0.5842 -1.3335)
			(stroke
				(width 0)
				(type default)
			)
			(fill no)
			(layer "F.Fab")
		)
		(pad "1" smd custom
			(at 0 -0.762)
			(size 0.2159 0.2159)
			(layers "F.Cu" "F.Mask" "F.Paste")
			(net "P5V_B_3")
			(options
				(clearance outline)
				(anchor circle)
			)
			(primitives
				(gr_poly
					(pts
						(arc
							(start -0.3302 -0.4318)
							(mid -0.402042 -0.402042)
							(end -0.4318 -0.3302)
						)
						(arc
							(start -0.4318 0.3302)
							(mid -0.402042 0.402042)
							(end -0.3302 0.4318)
						)
						(arc
							(start 0.3302 0.4318)
							(mid 0.402042 0.402042)
							(end 0.4318 0.3302)
						)
						(arc
							(start 0.4318 -0.3302)
							(mid 0.402042 -0.402042)
							(end 0.3302 -0.4318)
						)
					)
					(width 0)
					(fill yes)
				)
			)
		)
		(pad "2" smd custom
			(at 0 0.762)
			(size 0.2159 0.2159)
			(layers "F.Cu" "F.Mask" "F.Paste")
			(net "FLT_HDD20")
			(options
				(clearance outline)
				(anchor circle)
			)
			(primitives
				(gr_poly
					(pts
						(arc
							(start -0.3302 -0.4318)
							(mid -0.402042 -0.402042)
							(end -0.4318 -0.3302)
						)
						(arc
							(start -0.4318 0.3302)
							(mid -0.402042 0.402042)
							(end -0.3302 0.4318)
						)
						(arc
							(start 0.3302 0.4318)
							(mid 0.402042 0.402042)
							(end 0.4318 0.3302)
						)
						(arc
							(start 0.4318 -0.3302)
							(mid 0.402042 -0.402042)
							(end 0.3302 -0.4318)
						)
					)
					(width 0)
					(fill yes)
				)
			)
		)
	)
	(footprint ""
		(layer "F.Cu")
		(at 455.93 -37.846 180)
		(property "Reference" "C472"
			(at 0 0 180)
			(layer "F.SilkS")
			(hide yes)
			(effects
				(font
					(size 1.27 1.27)
				)
			)
		)
		(property "Value" "SC1U16V3KX-5GP"
			(at 0 -2.8194 180)
			(unlocked yes)
			(layer "F.Fab")
			(hide yes)
			(effects
				(font
					(size 1.016 1.016)
					(thickness 0.1524)
				)
			)
		)
		(property "Device Type" "C603H36"
			(at 0 -4.3434 180)
			(unlocked yes)
			(layer "F.Fab")
			(hide yes)
			(effects
				(font
					(size 1.016 1.016)
					(thickness 0.1524)
				)
			)
		)
		(duplicate_pad_numbers_are_jumpers no)
		(fp_line
			(start 0.508 0)
			(end -0.508 0)
			(stroke
				(width 0.2032)
				(type default)
			)
			(layer "F.SilkS")
		)
		(fp_rect
			(start -0.5842 1.3335)
			(end 0.5842 -1.3335)
			(stroke
				(width 0)
				(type default)
			)
			(fill no)
			(layer "F.CrtYd")
		)
		(fp_rect
			(start -0.5842 1.3335)
			(end 0.5842 -1.3335)
			(stroke
				(width 0)
				(type default)
			)
			(fill no)
			(layer "F.Fab")
		)
		(pad "1" smd custom
			(at 0 -0.762 180)
			(size 0.2159 0.2159)
			(layers "F.Cu" "F.Mask" "F.Paste")
			(net "P5V_HDD34")
			(options
				(clearance outline)
				(anchor circle)
			)
			(primitives
				(gr_poly
					(pts
						(arc
							(start -0.3302 -0.4318)
							(mid -0.402042 -0.402042)
							(end -0.4318 -0.3302)
						)
						(arc
							(start -0.4318 0.3302)
							(mid -0.402042 0.402042)
							(end -0.3302 0.4318)
						)
						(arc
							(start 0.3302 0.4318)
							(mid 0.402042 0.402042)
							(end 0.4318 0.3302)
						)
						(arc
							(start 0.4318 -0.3302)
							(mid 0.402042 -0.402042)
							(end 0.3302 -0.4318)
						)
					)
					(width 0)
					(fill yes)
				)
			)
		)
		(pad "2" smd custom
			(at 0 0.762 180)
			(size 0.2159 0.2159)
			(layers "F.Cu" "F.Mask" "F.Paste")
			(net "GND")
			(options
				(clearance outline)
				(anchor circle)
			)
			(primitives
				(gr_poly
					(pts
						(arc
							(start -0.3302 -0.4318)
							(mid -0.402042 -0.402042)
							(end -0.4318 -0.3302)
						)
						(arc
							(start -0.4318 0.3302)
							(mid -0.402042 0.402042)
							(end -0.3302 0.4318)
						)
						(arc
							(start 0.3302 0.4318)
							(mid 0.402042 0.402042)
							(end 0.4318 0.3302)
						)
						(arc
							(start 0.4318 -0.3302)
							(mid 0.402042 -0.402042)
							(end 0.3302 -0.4318)
						)
					)
					(width 0)
					(fill yes)
				)
			)
		)
	)
	(footprint ""
		(layer "F.Cu")
		(at 231.267 -198.8312 90)
		(property "Reference" "R71"
			(at 0 0 90)
			(layer "F.SilkS")
			(hide yes)
			(effects
				(font
					(size 1.27 1.27)
				)
			)
		)
		(property "Value" "4K7R2F-GP"
			(at 0.064008 -3.993896 90)
			(unlocked yes)
			(layer "F.Fab")
			(hide yes)
			(effects
				(font
					(size 1.016 1.016)
					(thickness 0.1524)
				)
			)
		)
		(property "Device Type" "R402H16"
			(at 0.064008 -5.517896 90)
			(unlocked yes)
			(layer "F.Fab")
			(hide yes)
			(effects
				(font
					(size 1.016 1.016)
					(thickness 0.1524)
				)
			)
		)
		(duplicate_pad_numbers_are_jumpers no)
		(fp_line
			(start 0.508 -0.9398)
			(end -0.508 -0.9398)
			(stroke
				(width 0.1524)
				(type default)
			)
			(layer "F.SilkS")
		)
		(fp_line
			(start -0.508 -0.9398)
			(end -0.508 0.9398)
			(stroke
				(width 0.1524)
				(type default)
			)
			(layer "F.SilkS")
		)
		(fp_rect
			(start -0.508 0.9398)
			(end 0.508 -0.9398)
			(stroke
				(width 0)
				(type default)
			)
			(fill no)
			(layer "F.CrtYd")
		)
		(fp_rect
			(start -0.508 0.9398)
			(end 0.508 -0.9398)
			(stroke
				(width 0)
				(type default)
			)
			(fill no)
			(layer "F.Fab")
		)
		(pad "1" smd custom
			(at 0 -0.4445 90)
			(size 0.1397 0.1397)
			(layers "F.Cu" "F.Mask" "F.Paste")
			(net "P3V3_STBY_B")
			(options
				(clearance outline)
				(anchor circle)
			)
			(primitives
				(gr_poly
					(pts
						(arc
							(start -0.1778 -0.2794)
							(mid -0.249642 -0.249642)
							(end -0.2794 -0.1778)
						)
						(arc
							(start -0.2794 0.1778)
							(mid -0.249642 0.249642)
							(end -0.1778 0.2794)
						)
						(arc
							(start 0.1778 0.2794)
							(mid 0.249642 0.249642)
							(end 0.2794 0.1778)
						)
						(arc
							(start 0.2794 -0.1778)
							(mid 0.249642 -0.249642)
							(end 0.1778 -0.2794)
						)
					)
					(width 0)
					(fill yes)
				)
			)
		)
		(pad "2" smd custom
			(at 0 0.4445 90)
			(size 0.1397 0.1397)
			(layers "F.Cu" "F.Mask" "F.Paste")
			(net "IO_EXP2_A0")
			(options
				(clearance outline)
				(anchor circle)
			)
			(primitives
				(gr_poly
					(pts
						(arc
							(start -0.1778 -0.2794)
							(mid -0.249642 -0.249642)
							(end -0.2794 -0.1778)
						)
						(arc
							(start -0.2794 0.1778)
							(mid -0.249642 0.249642)
							(end -0.1778 0.2794)
						)
						(arc
							(start 0.1778 0.2794)
							(mid 0.249642 0.249642)
							(end 0.2794 0.1778)
						)
						(arc
							(start 0.2794 -0.1778)
							(mid 0.249642 -0.249642)
							(end 0.1778 -0.2794)
						)
					)
					(width 0)
					(fill yes)
				)
			)
		)
	)
	(footprint ""
		(layer "F.Cu")
		(at 444.513208 -112.710976 90)
		(property "Reference" "C679"
			(at 0 0 90)
			(layer "F.SilkS")
			(hide yes)
			(effects
				(font
					(size 1.27 1.27)
				)
			)
		)
		(property "Value" "SCD1U16V2KX-3GP"
			(at 1.1811 -2.7051 90)
			(unlocked yes)
			(layer "F.Fab")
			(hide yes)
			(effects
				(font
					(size 1.016 1.016)
					(thickness 0.1524)
				)
			)
		)
		(property "Device Type" "C402H22"
			(at 1.1811 -4.2291 90)
			(unlocked yes)
			(layer "F.Fab")
			(hide yes)
			(effects
				(font
					(size 1.016 1.016)
					(thickness 0.1524)
				)
			)
		)
		(duplicate_pad_numbers_are_jumpers no)
		(fp_rect
			(start -0.4318 0.9525)
			(end 0.4318 -0.9525)
			(stroke
				(width 0)
				(type default)
			)
			(fill no)
			(layer "F.CrtYd")
		)
		(fp_rect
			(start -0.4318 0.9525)
			(end 0.4318 -0.9525)
			(stroke
				(width 0)
				(type default)
			)
			(fill no)
			(layer "F.Fab")
		)
		(pad "1" smd custom
			(at 0 -0.4445 90)
			(size 0.1524 0.1524)
			(layers "F.Cu" "F.Mask" "F.Paste")
			(net "P5V_B_4_VBST_RC")
			(options
				(clearance outline)
				(anchor circle)
			)
			(primitives
				(gr_poly
					(pts
						(arc
							(start 0.3048 -0.2032)
							(mid 0.275042 -0.275042)
							(end 0.2032 -0.3048)
						)
						(arc
							(start -0.2032 -0.3048)
							(mid -0.275042 -0.275042)
							(end -0.3048 -0.2032)
						)
						(arc
							(start -0.3048 0.2032)
							(mid -0.275042 0.275042)
							(end -0.2032 0.3048)
						)
						(arc
							(start 0.2032 0.3048)
							(mid 0.275042 0.275042)
							(end 0.3048 0.2032)
						)
					)
					(width 0)
					(fill yes)
				)
			)
		)
		(pad "2" smd custom
			(at 0 0.4445 90)
			(size 0.1524 0.1524)
			(layers "F.Cu" "F.Mask" "F.Paste")
			(net "P5V_B_4_LL")
			(options
				(clearance outline)
				(anchor circle)
			)
			(primitives
				(gr_poly
					(pts
						(arc
							(start 0.3048 -0.2032)
							(mid 0.275042 -0.275042)
							(end 0.2032 -0.3048)
						)
						(arc
							(start -0.2032 -0.3048)
							(mid -0.275042 -0.275042)
							(end -0.3048 -0.2032)
						)
						(arc
							(start -0.3048 0.2032)
							(mid -0.275042 0.275042)
							(end -0.2032 0.3048)
						)
						(arc
							(start 0.2032 0.3048)
							(mid 0.275042 0.275042)
							(end 0.3048 0.2032)
						)
					)
					(width 0)
					(fill yes)
				)
			)
		)
	)
	(footprint ""
		(layer "F.Cu")
		(at 221.73946 -165.40226 -90)
		(property "Reference" "R55"
			(at 0 0 270)
			(layer "F.SilkS")
			(hide yes)
			(effects
				(font
					(size 1.27 1.27)
				)
			)
		)
		(property "Value" "4K7R2F-GP"
			(at 0.064008 -3.993896 270)
			(unlocked yes)
			(layer "F.Fab")
			(hide yes)
			(effects
				(font
					(size 1.016 1.016)
					(thickness 0.1524)
				)
			)
		)
		(property "Device Type" "R402H16"
			(at 0.064008 -5.517896 270)
			(unlocked yes)
			(layer "F.Fab")
			(hide yes)
			(effects
				(font
					(size 1.016 1.016)
					(thickness 0.1524)
				)
			)
		)
		(duplicate_pad_numbers_are_jumpers no)
		(fp_line
			(start -0.508 -0.9398)
			(end -0.508 0.9398)
			(stroke
				(width 0.1524)
				(type default)
			)
			(layer "F.SilkS")
		)
		(fp_line
			(start 0.508 -0.9398)
			(end -0.508 -0.9398)
			(stroke
				(width 0.1524)
				(type default)
			)
			(layer "F.SilkS")
		)
		(fp_rect
			(start -0.508 0.9398)
			(end 0.508 -0.9398)
			(stroke
				(width 0)
				(type default)
			)
			(fill no)
			(layer "F.CrtYd")
		)
		(fp_rect
			(start -0.508 0.9398)
			(end 0.508 -0.9398)
			(stroke
				(width 0)
				(type default)
			)
			(fill no)
			(layer "F.Fab")
		)
		(pad "1" smd custom
			(at 0 -0.4445 270)
			(size 0.1397 0.1397)
			(layers "F.Cu" "F.Mask" "F.Paste")
			(net "P3V3_STBY_B")
			(options
				(clearance outline)
				(anchor circle)
			)
			(primitives
				(gr_poly
					(pts
						(arc
							(start -0.1778 -0.2794)
							(mid -0.249642 -0.249642)
							(end -0.2794 -0.1778)
						)
						(arc
							(start -0.2794 0.1778)
							(mid -0.249642 0.249642)
							(end -0.1778 0.2794)
						)
						(arc
							(start 0.1778 0.2794)
							(mid 0.249642 0.249642)
							(end 0.2794 0.1778)
						)
						(arc
							(start 0.2794 -0.1778)
							(mid 0.249642 -0.249642)
							(end 0.1778 -0.2794)
						)
					)
					(width 0)
					(fill yes)
				)
			)
		)
		(pad "2" smd custom
			(at 0 0.4445 270)
			(size 0.1397 0.1397)
			(layers "F.Cu" "F.Mask" "F.Paste")
			(net "IO_EXP6_A2")
			(options
				(clearance outline)
				(anchor circle)
			)
			(primitives
				(gr_poly
					(pts
						(arc
							(start -0.1778 -0.2794)
							(mid -0.249642 -0.249642)
							(end -0.2794 -0.1778)
						)
						(arc
							(start -0.2794 0.1778)
							(mid -0.249642 0.249642)
							(end -0.1778 0.2794)
						)
						(arc
							(start 0.1778 0.2794)
							(mid 0.249642 0.249642)
							(end 0.2794 0.1778)
						)
						(arc
							(start 0.2794 -0.1778)
							(mid 0.249642 -0.249642)
							(end 0.1778 -0.2794)
						)
					)
					(width 0)
					(fill yes)
				)
			)
		)
	)
)
